(kicad_pcb
	(version 20260206)
	(generator "pcbnew")
	(generator_version "10.0")
	(general
		(thickness 1.6)
		(legacy_teardrops no)
	)
	(paper "A4")
	(title_block
		(title "03242023_DA0F0TMBIJ0_F0T_Motherboard_J_brd_V01_OCP.brd")
		(comment 1 "Grand Teton / footprints 5987-5992 of 6105")
	)
	(layers
		(0 "F.Cu" signal "TOP")
		(4 "In1.Cu" signal "GND")
		(6 "In2.Cu" signal "IN1")
		(8 "In3.Cu" signal "GND1")
		(10 "In4.Cu" signal "IN2")
		(12 "In5.Cu" signal "GND2")
		(14 "In6.Cu" signal "IN3")
		(16 "In7.Cu" signal "GND3")
		(18 "In8.Cu" signal "VCC")
		(20 "In9.Cu" signal "VCC1")
		(22 "In10.Cu" signal "GND4")
		(24 "In11.Cu" signal "IN4")
		(26 "In12.Cu" signal "GND5")
		(28 "In13.Cu" signal "IN5")
		(30 "In14.Cu" signal "GND6")
		(32 "In15.Cu" signal "IN6")
		(34 "In16.Cu" signal "GND7")
		(2 "B.Cu" signal "BOTTOM")
		(9 "F.Adhes" user "F.Adhesive")
		(11 "B.Adhes" user "B.Adhesive")
		(13 "F.Paste" user "Package Geometry/Pastemask Top")
		(15 "B.Paste" user "Package Geometry/Pastemask Bottom")
		(5 "F.SilkS" user "Ref Des/Silkscreen Top")
		(7 "B.SilkS" user "Ref Des/Silkscreen Bottom")
		(1 "F.Mask" user "Board Geometry/Soldermask Top")
		(3 "B.Mask" user "Board Geometry/Soldermask Bottom")
		(17 "Dwgs.User" user "User.Drawings")
		(19 "Cmts.User" user "User.Comments")
		(21 "Eco1.User" user "User.Eco1")
		(23 "Eco2.User" user "User.Eco2")
		(25 "Edge.Cuts" user "Board Geometry/Outline")
		(27 "Margin" user)
		(31 "F.CrtYd" user "Package Geometry/Place Bound Top")
		(29 "B.CrtYd" user "Package Geometry/Place Bound Bottom")
		(35 "F.Fab" user "Ref Des/Assembly Top")
		(33 "B.Fab" user "Ref Des/Assembly Bottom")
	)
	(footprint ""
		(layer "B.Cu")
		(at 209.770218 -193.09461)
		(property "Reference" "C542"
			(at 0 0 0)
			(layer "B.SilkS")
			(hide yes)
			(effects
				(font
					(size 1.27 1.27)
				)
				(justify mirror)
			)
		)
		(property "Value" ""
			(at 0 0 0)
			(layer "B.Fab")
			(effects
				(font
					(size 1.27 1.27)
				)
				(justify mirror)
			)
		)
		(duplicate_pad_numbers_are_jumpers no)
		(fp_line
			(start -0.7874 -0.4064)
			(end -0.7874 0.4064)
			(stroke
				(width 0.1524)
				(type default)
			)
			(layer "B.SilkS")
		)
		(fp_line
			(start -0.7874 0.4064)
			(end 0.7874 0.4064)
			(stroke
				(width 0.1524)
				(type default)
			)
			(layer "B.SilkS")
		)
		(fp_line
			(start 0.7874 -0.4064)
			(end -0.7874 -0.4064)
			(stroke
				(width 0.1524)
				(type default)
			)
			(layer "B.SilkS")
		)
		(fp_line
			(start 0.7874 0.4064)
			(end 0.7874 -0.4064)
			(stroke
				(width 0.1524)
				(type default)
			)
			(layer "B.SilkS")
		)
		(fp_line
			(start -0.67945 -0.3048)
			(end -0.67945 0.3048)
			(stroke
				(width 0.1)
				(type default)
			)
			(layer "B.Fab")
		)
		(fp_line
			(start -0.67945 0.3048)
			(end -0.120396 0.3048)
			(stroke
				(width 0.1)
				(type default)
			)
			(layer "B.Fab")
		)
		(fp_line
			(start -0.12065 -0.3048)
			(end -0.67945 -0.3048)
			(stroke
				(width 0.1)
				(type default)
			)
			(layer "B.Fab")
		)
		(fp_line
			(start -0.12065 -0.2794)
			(end -0.12065 -0.3048)
			(stroke
				(width 0.1)
				(type default)
			)
			(layer "B.Fab")
		)
		(fp_line
			(start -0.120396 0.2794)
			(end 0.12065 0.2794)
			(stroke
				(width 0.1)
				(type default)
			)
			(layer "B.Fab")
		)
		(fp_line
			(start -0.120396 0.3048)
			(end -0.120396 0.2794)
			(stroke
				(width 0.1)
				(type default)
			)
			(layer "B.Fab")
		)
		(fp_line
			(start 0.12065 -0.305054)
			(end 0.12065 -0.2794)
			(stroke
				(width 0.1)
				(type default)
			)
			(layer "B.Fab")
		)
		(fp_line
			(start 0.12065 -0.2794)
			(end -0.12065 -0.2794)
			(stroke
				(width 0.1)
				(type default)
			)
			(layer "B.Fab")
		)
		(fp_line
			(start 0.12065 0.2794)
			(end 0.12065 0.3048)
			(stroke
				(width 0.1)
				(type default)
			)
			(layer "B.Fab")
		)
		(fp_line
			(start 0.12065 0.3048)
			(end 0.67945 0.3048)
			(stroke
				(width 0.1)
				(type default)
			)
			(layer "B.Fab")
		)
		(fp_line
			(start 0.67945 -0.305054)
			(end 0.12065 -0.305054)
			(stroke
				(width 0.1)
				(type default)
			)
			(layer "B.Fab")
		)
		(fp_line
			(start 0.67945 0.3048)
			(end 0.67945 -0.305054)
			(stroke
				(width 0.1)
				(type default)
			)
			(layer "B.Fab")
		)
		(pad "1" smd circle
			(at 0.40005 0 180)
			(size 0 0)
			(layers "B.Cu" "B.Mask" "B.Paste")
			(net "P3V3_AUX")
		)
		(pad "2" smd circle
			(at -0.40005 0 180)
			(size 0 0)
			(layers "B.Cu" "B.Mask" "B.Paste")
			(net "GND")
		)
	)
	(footprint ""
		(layer "B.Cu")
		(at 119.083074 -324.990714 -90)
		(property "Reference" "PC572_P1_1"
			(at 0 0 90)
			(layer "B.SilkS")
			(hide yes)
			(effects
				(font
					(size 1.27 1.27)
				)
				(justify mirror)
			)
		)
		(property "Value" ""
			(at 0 0 90)
			(layer "B.Fab")
			(effects
				(font
					(size 1.27 1.27)
				)
				(justify mirror)
			)
		)
		(duplicate_pad_numbers_are_jumpers no)
		(fp_line
			(start -0.7874 0.4064)
			(end 0.7874 0.4064)
			(stroke
				(width 0.1524)
				(type default)
			)
			(layer "B.SilkS")
		)
		(fp_line
			(start 0.7874 0.4064)
			(end 0.7874 -0.4064)
			(stroke
				(width 0.1524)
				(type default)
			)
			(layer "B.SilkS")
		)
		(fp_line
			(start -0.7874 -0.4064)
			(end -0.7874 0.4064)
			(stroke
				(width 0.1524)
				(type default)
			)
			(layer "B.SilkS")
		)
		(fp_line
			(start 0.7874 -0.4064)
			(end -0.7874 -0.4064)
			(stroke
				(width 0.1524)
				(type default)
			)
			(layer "B.SilkS")
		)
		(fp_line
			(start -0.67945 0.3048)
			(end -0.120396 0.3048)
			(stroke
				(width 0.1)
				(type default)
			)
			(layer "B.Fab")
		)
		(fp_line
			(start -0.120396 0.3048)
			(end -0.120396 0.2794)
			(stroke
				(width 0.1)
				(type default)
			)
			(layer "B.Fab")
		)
		(fp_line
			(start 0.12065 0.3048)
			(end 0.67945 0.3048)
			(stroke
				(width 0.1)
				(type default)
			)
			(layer "B.Fab")
		)
		(fp_line
			(start 0.67945 0.3048)
			(end 0.67945 -0.305054)
			(stroke
				(width 0.1)
				(type default)
			)
			(layer "B.Fab")
		)
		(fp_line
			(start -0.120396 0.2794)
			(end 0.12065 0.2794)
			(stroke
				(width 0.1)
				(type default)
			)
			(layer "B.Fab")
		)
		(fp_line
			(start 0.12065 0.2794)
			(end 0.12065 0.3048)
			(stroke
				(width 0.1)
				(type default)
			)
			(layer "B.Fab")
		)
		(fp_line
			(start -0.12065 -0.2794)
			(end -0.12065 -0.3048)
			(stroke
				(width 0.1)
				(type default)
			)
			(layer "B.Fab")
		)
		(fp_line
			(start 0.12065 -0.2794)
			(end -0.12065 -0.2794)
			(stroke
				(width 0.1)
				(type default)
			)
			(layer "B.Fab")
		)
		(fp_line
			(start -0.67945 -0.3048)
			(end -0.67945 0.3048)
			(stroke
				(width 0.1)
				(type default)
			)
			(layer "B.Fab")
		)
		(fp_line
			(start -0.12065 -0.3048)
			(end -0.67945 -0.3048)
			(stroke
				(width 0.1)
				(type default)
			)
			(layer "B.Fab")
		)
		(fp_line
			(start 0.12065 -0.305054)
			(end 0.12065 -0.2794)
			(stroke
				(width 0.1)
				(type default)
			)
			(layer "B.Fab")
		)
		(fp_line
			(start 0.67945 -0.305054)
			(end 0.12065 -0.305054)
			(stroke
				(width 0.1)
				(type default)
			)
			(layer "B.Fab")
		)
		(pad "1" smd circle
			(at 0.40005 0 90)
			(size 0 0)
			(layers "B.Cu" "B.Mask" "B.Paste")
			(net "PVCCIN_CPU1")
		)
		(pad "2" smd circle
			(at -0.40005 0 90)
			(size 0 0)
			(layers "B.Cu" "B.Mask" "B.Paste")
			(net "GND")
		)
	)
	(footprint ""
		(layer "B.Cu")
		(at 19.588734 -176.423574 -90)
		(property "Reference" "R2385"
			(at 0 0 90)
			(layer "B.SilkS")
			(hide yes)
			(effects
				(font
					(size 1.27 1.27)
				)
				(justify mirror)
			)
		)
		(property "Value" ""
			(at 0 0 90)
			(layer "B.Fab")
			(effects
				(font
					(size 1.27 1.27)
				)
				(justify mirror)
			)
		)
		(duplicate_pad_numbers_are_jumpers no)
		(fp_line
			(start -0.7874 0.4064)
			(end 0.7874 0.4064)
			(stroke
				(width 0.1524)
				(type default)
			)
			(layer "B.SilkS")
		)
		(fp_line
			(start 0.7874 0.4064)
			(end 0.7874 -0.4064)
			(stroke
				(width 0.1524)
				(type default)
			)
			(layer "B.SilkS")
		)
		(fp_line
			(start -0.7874 -0.4064)
			(end -0.7874 0.4064)
			(stroke
				(width 0.1524)
				(type default)
			)
			(layer "B.SilkS")
		)
		(fp_line
			(start 0.7874 -0.4064)
			(end -0.7874 -0.4064)
			(stroke
				(width 0.1524)
				(type default)
			)
			(layer "B.SilkS")
		)
		(fp_line
			(start -0.67945 0.3048)
			(end -0.120396 0.3048)
			(stroke
				(width 0.1)
				(type default)
			)
			(layer "B.Fab")
		)
		(fp_line
			(start -0.120396 0.3048)
			(end -0.120396 0.2794)
			(stroke
				(width 0.1)
				(type default)
			)
			(layer "B.Fab")
		)
		(fp_line
			(start 0.12065 0.3048)
			(end 0.67945 0.3048)
			(stroke
				(width 0.1)
				(type default)
			)
			(layer "B.Fab")
		)
		(fp_line
			(start 0.67945 0.3048)
			(end 0.67945 -0.305054)
			(stroke
				(width 0.1)
				(type default)
			)
			(layer "B.Fab")
		)
		(fp_line
			(start -0.120396 0.2794)
			(end 0.12065 0.2794)
			(stroke
				(width 0.1)
				(type default)
			)
			(layer "B.Fab")
		)
		(fp_line
			(start 0.12065 0.2794)
			(end 0.12065 0.3048)
			(stroke
				(width 0.1)
				(type default)
			)
			(layer "B.Fab")
		)
		(fp_line
			(start -0.12065 -0.2794)
			(end -0.12065 -0.3048)
			(stroke
				(width 0.1)
				(type default)
			)
			(layer "B.Fab")
		)
		(fp_line
			(start 0.12065 -0.2794)
			(end -0.12065 -0.2794)
			(stroke
				(width 0.1)
				(type default)
			)
			(layer "B.Fab")
		)
		(fp_line
			(start -0.67945 -0.3048)
			(end -0.67945 0.3048)
			(stroke
				(width 0.1)
				(type default)
			)
			(layer "B.Fab")
		)
		(fp_line
			(start -0.12065 -0.3048)
			(end -0.67945 -0.3048)
			(stroke
				(width 0.1)
				(type default)
			)
			(layer "B.Fab")
		)
		(fp_line
			(start 0.12065 -0.305054)
			(end 0.12065 -0.2794)
			(stroke
				(width 0.1)
				(type default)
			)
			(layer "B.Fab")
		)
		(fp_line
			(start 0.67945 -0.305054)
			(end 0.12065 -0.305054)
			(stroke
				(width 0.1)
				(type default)
			)
			(layer "B.Fab")
		)
		(pad "1" smd circle
			(at 0.40005 0 90)
			(size 0 0)
			(layers "B.Cu" "B.Mask" "B.Paste")
			(net "FM_PVNN_MAIN_CPU1_EN")
		)
		(pad "2" smd circle
			(at -0.40005 0 90)
			(size 0 0)
			(layers "B.Cu" "B.Mask" "B.Paste")
			(net "GND")
		)
	)
	(footprint ""
		(layer "B.Cu")
		(at 11.961114 -98.296222 180)
		(property "Reference" "C2034"
			(at 0 0 0)
			(layer "B.SilkS")
			(hide yes)
			(effects
				(font
					(size 1.27 1.27)
				)
				(justify mirror)
			)
		)
		(property "Value" ""
			(at 0 0 0)
			(layer "B.Fab")
			(effects
				(font
					(size 1.27 1.27)
				)
				(justify mirror)
			)
		)
		(duplicate_pad_numbers_are_jumpers no)
		(fp_line
			(start 0.7874 0.4064)
			(end 0.7874 -0.4064)
			(stroke
				(width 0.1524)
				(type default)
			)
			(layer "B.SilkS")
		)
		(fp_line
			(start 0.7874 -0.4064)
			(end -0.7874 -0.4064)
			(stroke
				(width 0.1524)
				(type default)
			)
			(layer "B.SilkS")
		)
		(fp_line
			(start -0.7874 0.4064)
			(end 0.7874 0.4064)
			(stroke
				(width 0.1524)
				(type default)
			)
			(layer "B.SilkS")
		)
		(fp_line
			(start -0.7874 -0.4064)
			(end -0.7874 0.4064)
			(stroke
				(width 0.1524)
				(type default)
			)
			(layer "B.SilkS")
		)
		(fp_line
			(start 0.67945 0.3048)
			(end 0.67945 -0.305054)
			(stroke
				(width 0.1)
				(type default)
			)
			(layer "B.Fab")
		)
		(fp_line
			(start 0.67945 -0.305054)
			(end 0.12065 -0.305054)
			(stroke
				(width 0.1)
				(type default)
			)
			(layer "B.Fab")
		)
		(fp_line
			(start 0.12065 0.3048)
			(end 0.67945 0.3048)
			(stroke
				(width 0.1)
				(type default)
			)
			(layer "B.Fab")
		)
		(fp_line
			(start 0.12065 0.2794)
			(end 0.12065 0.3048)
			(stroke
				(width 0.1)
				(type default)
			)
			(layer "B.Fab")
		)
		(fp_line
			(start 0.12065 -0.2794)
			(end -0.12065 -0.2794)
			(stroke
				(width 0.1)
				(type default)
			)
			(layer "B.Fab")
		)
		(fp_line
			(start 0.12065 -0.305054)
			(end 0.12065 -0.2794)
			(stroke
				(width 0.1)
				(type default)
			)
			(layer "B.Fab")
		)
		(fp_line
			(start -0.120396 0.3048)
			(end -0.120396 0.2794)
			(stroke
				(width 0.1)
				(type default)
			)
			(layer "B.Fab")
		)
		(fp_line
			(start -0.120396 0.2794)
			(end 0.12065 0.2794)
			(stroke
				(width 0.1)
				(type default)
			)
			(layer "B.Fab")
		)
		(fp_line
			(start -0.12065 -0.2794)
			(end -0.12065 -0.3048)
			(stroke
				(width 0.1)
				(type default)
			)
			(layer "B.Fab")
		)
		(fp_line
			(start -0.12065 -0.3048)
			(end -0.67945 -0.3048)
			(stroke
				(width 0.1)
				(type default)
			)
			(layer "B.Fab")
		)
		(fp_line
			(start -0.67945 0.3048)
			(end -0.120396 0.3048)
			(stroke
				(width 0.1)
				(type default)
			)
			(layer "B.Fab")
		)
		(fp_line
			(start -0.67945 -0.3048)
			(end -0.67945 0.3048)
			(stroke
				(width 0.1)
				(type default)
			)
			(layer "B.Fab")
		)
		(pad "1" smd circle
			(at 0.40005 0)
			(size 0 0)
			(layers "B.Cu" "B.Mask" "B.Paste")
			(net "P3V3_AUX_USB_HUB")
		)
		(pad "2" smd circle
			(at -0.40005 0)
			(size 0 0)
			(layers "B.Cu" "B.Mask" "B.Paste")
			(net "GND")
		)
	)
	(footprint ""
		(layer "B.Cu")
		(at 323.407278 -186.70651 -90)
		(property "Reference" "R301"
			(at 0 0 90)
			(layer "B.SilkS")
			(hide yes)
			(effects
				(font
					(size 1.27 1.27)
				)
				(justify mirror)
			)
		)
		(property "Value" ""
			(at 0 0 90)
			(layer "B.Fab")
			(effects
				(font
					(size 1.27 1.27)
				)
				(justify mirror)
			)
		)
		(duplicate_pad_numbers_are_jumpers no)
		(fp_line
			(start -0.7874 0.4064)
			(end 0.7874 0.4064)
			(stroke
				(width 0.1524)
				(type default)
			)
			(layer "B.SilkS")
		)
		(fp_line
			(start 0.7874 0.4064)
			(end 0.7874 -0.4064)
			(stroke
				(width 0.1524)
				(type default)
			)
			(layer "B.SilkS")
		)
		(fp_line
			(start -0.7874 -0.4064)
			(end -0.7874 0.4064)
			(stroke
				(width 0.1524)
				(type default)
			)
			(layer "B.SilkS")
		)
		(fp_line
			(start 0.7874 -0.4064)
			(end -0.7874 -0.4064)
			(stroke
				(width 0.1524)
				(type default)
			)
			(layer "B.SilkS")
		)
		(fp_line
			(start -0.67945 0.3048)
			(end -0.120396 0.3048)
			(stroke
				(width 0.1)
				(type default)
			)
			(layer "B.Fab")
		)
		(fp_line
			(start -0.120396 0.3048)
			(end -0.120396 0.2794)
			(stroke
				(width 0.1)
				(type default)
			)
			(layer "B.Fab")
		)
		(fp_line
			(start 0.12065 0.3048)
			(end 0.67945 0.3048)
			(stroke
				(width 0.1)
				(type default)
			)
			(layer "B.Fab")
		)
		(fp_line
			(start 0.67945 0.3048)
			(end 0.67945 -0.305054)
			(stroke
				(width 0.1)
				(type default)
			)
			(layer "B.Fab")
		)
		(fp_line
			(start -0.120396 0.2794)
			(end 0.12065 0.2794)
			(stroke
				(width 0.1)
				(type default)
			)
			(layer "B.Fab")
		)
		(fp_line
			(start 0.12065 0.2794)
			(end 0.12065 0.3048)
			(stroke
				(width 0.1)
				(type default)
			)
			(layer "B.Fab")
		)
		(fp_line
			(start -0.12065 -0.2794)
			(end -0.12065 -0.3048)
			(stroke
				(width 0.1)
				(type default)
			)
			(layer "B.Fab")
		)
		(fp_line
			(start 0.12065 -0.2794)
			(end -0.12065 -0.2794)
			(stroke
				(width 0.1)
				(type default)
			)
			(layer "B.Fab")
		)
		(fp_line
			(start -0.67945 -0.3048)
			(end -0.67945 0.3048)
			(stroke
				(width 0.1)
				(type default)
			)
			(layer "B.Fab")
		)
		(fp_line
			(start -0.12065 -0.3048)
			(end -0.67945 -0.3048)
			(stroke
				(width 0.1)
				(type default)
			)
			(layer "B.Fab")
		)
		(fp_line
			(start 0.12065 -0.305054)
			(end 0.12065 -0.2794)
			(stroke
				(width 0.1)
				(type default)
			)
			(layer "B.Fab")
		)
		(fp_line
			(start 0.67945 -0.305054)
			(end 0.12065 -0.305054)
			(stroke
				(width 0.1)
				(type default)
			)
			(layer "B.Fab")
		)
		(pad "1" smd circle
			(at 0.40005 0 90)
			(size 0 0)
			(layers "B.Cu" "B.Mask" "B.Paste")
			(net "PVNN_TERM_CPU0")
		)
		(pad "2" smd circle
			(at -0.40005 0 90)
			(size 0 0)
			(layers "B.Cu" "B.Mask" "B.Paste")
			(net "H_CPU_RMCA_LVC1_R_N")
		)
	)
	(footprint ""
		(layer "B.Cu")
		(at 74.347324 -190.705232 90)
		(property "Reference" "R52"
			(at 0 0 90)
			(layer "B.SilkS")
			(hide yes)
			(effects
				(font
					(size 1.27 1.27)
				)
				(justify mirror)
			)
		)
		(property "Value" ""
			(at 0 0 90)
			(layer "B.Fab")
			(effects
				(font
					(size 1.27 1.27)
				)
				(justify mirror)
			)
		)
		(duplicate_pad_numbers_are_jumpers no)
		(fp_line
			(start 0.7874 -0.4064)
			(end -0.7874 -0.4064)
			(stroke
				(width 0.1524)
				(type default)
			)
			(layer "B.SilkS")
		)
		(fp_line
			(start -0.7874 -0.4064)
			(end -0.7874 0.4064)
			(stroke
				(width 0.1524)
				(type default)
			)
			(layer "B.SilkS")
		)
		(fp_line
			(start 0.7874 0.4064)
			(end 0.7874 -0.4064)
			(stroke
				(width 0.1524)
				(type default)
			)
			(layer "B.SilkS")
		)
		(fp_line
			(start -0.7874 0.4064)
			(end 0.7874 0.4064)
			(stroke
				(width 0.1524)
				(type default)
			)
			(layer "B.SilkS")
		)
		(fp_line
			(start 0.67945 -0.305054)
			(end 0.12065 -0.305054)
			(stroke
				(width 0.1)
				(type default)
			)
			(layer "B.Fab")
		)
		(fp_line
			(start 0.12065 -0.305054)
			(end 0.12065 -0.2794)
			(stroke
				(width 0.1)
				(type default)
			)
			(layer "B.Fab")
		)
		(fp_line
			(start -0.12065 -0.3048)
			(end -0.67945 -0.3048)
			(stroke
				(width 0.1)
				(type default)
			)
			(layer "B.Fab")
		)
		(fp_line
			(start -0.67945 -0.3048)
			(end -0.67945 0.3048)
			(stroke
				(width 0.1)
				(type default)
			)
			(layer "B.Fab")
		)
		(fp_line
			(start 0.12065 -0.2794)
			(end -0.12065 -0.2794)
			(stroke
				(width 0.1)
				(type default)
			)
			(layer "B.Fab")
		)
		(fp_line
			(start -0.12065 -0.2794)
			(end -0.12065 -0.3048)
			(stroke
				(width 0.1)
				(type default)
			)
			(layer "B.Fab")
		)
		(fp_line
			(start 0.12065 0.2794)
			(end 0.12065 0.3048)
			(stroke
				(width 0.1)
				(type default)
			)
			(layer "B.Fab")
		)
		(fp_line
			(start -0.120396 0.2794)
			(end 0.12065 0.2794)
			(stroke
				(width 0.1)
				(type default)
			)
			(layer "B.Fab")
		)
		(fp_line
			(start 0.67945 0.3048)
			(end 0.67945 -0.305054)
			(stroke
				(width 0.1)
				(type default)
			)
			(layer "B.Fab")
		)
		(fp_line
			(start 0.12065 0.3048)
			(end 0.67945 0.3048)
			(stroke
				(width 0.1)
				(type default)
			)
			(layer "B.Fab")
		)
		(fp_line
			(start -0.120396 0.3048)
			(end -0.120396 0.2794)
			(stroke
				(width 0.1)
				(type default)
			)
			(layer "B.Fab")
		)
		(fp_line
			(start -0.67945 0.3048)
			(end -0.120396 0.3048)
			(stroke
				(width 0.1)
				(type default)
			)
			(layer "B.Fab")
		)
		(pad "1" smd circle
			(at 0.40005 0 270)
			(size 0 0)
			(layers "B.Cu" "B.Mask" "B.Paste")
			(net "DBP_CPU1_MBP1_GTL_R_N")
		)
		(pad "2" smd circle
			(at -0.40005 0 270)
			(size 0 0)
			(layers "B.Cu" "B.Mask" "B.Paste")
			(net "DBP_CPU_MBP1_GTL_N")
		)
	)
)
